FILE_TYPE = CONNECTIVITY;
{Allegro Design Entry HDL 17.4-2019 S026 (4007227) 1/17/2022}
"PAGE_NUMBER" = 431;
0"NC";
1"P1V8_CPU0_RT_1D\g";
2"GND\g";
3"GND\g";
4"GND\g";
5"P0V9_CPU0_RT3_2A_2D\g";
6"P1V8_CPU0_RT3_1A\g";
7"P0V9_CPU0_RT3_2A\g";
8"GND\g";
9"NCF_A1_CPU0_P3_GND";
10"NCF_CPU0_P3_GND";
11"GND\g";
12"P0V9_CPU0_RT_2D\g";
13"P1V8_CPU0_RT3_1A_1D\g";
14"RT_CPU0_P3_VQPS";
%"P1V0"
"1","(-8575,4075)","0","pure_quanta_power","I1";
;
HDL_POWER"P1V8_CPU0_RT_1D"
CDS_LIB"pure_quanta_power";
"A"1;
%"VCC_CORE"
"1","(-4575,4975)","0","pure_quanta_power","I10";
;
HDL_POWER"P0V9_CPU0_RT3_2A"
CDS_LIB"pure_quanta_power";
"A"7;
%"UNIVERSAL_GND"
"1","(-3025,1275)","0","pure_quanta_power","I11";
;
CDS_LIB"pure_quanta_power"
HDL_POWER"GND";
"A"8;
%"UNIVERSAL_GND"
"1","(-1350,900)","0","pure_quanta_power","I12";
;
CDS_LIB"pure_quanta_power"
HDL_POWER"GND";
"A"2;
%"Q_RES"
"2","(-1350,1200)","0","pure_quanta","I13";
;
LOCATION"R1125"
$SEC"1"
CDS_SEC"1"
TOLERANCE"5%"
MATERIAL"CHIP"
WATTAGE"1/20W"
VALUE"0"
PACK_TYPE"0201LF"
CDS_LIB"pure_quanta"
PART_NUMBER"CS00001JE10";
"A"
$PN"1"10;
"B"
$PN"2"2;
%"Q_RES"
"2","(-1200,1750)","0","pure_quanta","I14";
;
LOCATION"R1126"
$SEC"1"
CDS_SEC"1"
MATERIAL"CHIP"
TOLERANCE"5%"
PACK_TYPE"0201LF"
VALUE"0"
WATTAGE"1/20W"
CDS_LIB"pure_quanta"
PART_NUMBER"CS00001JE10";
"A"
$PN"1"9;
"B"
$PN"2"3;
%"UNIVERSAL_GND"
"1","(-1200,1450)","0","pure_quanta_power","I15";
;
CDS_LIB"pure_quanta_power"
HDL_POWER"GND";
"A"3;
%"UNIVERSAL_GND"
"1","(-975,2000)","0","pure_quanta_power","I16";
;
CDS_LIB"pure_quanta_power"
HDL_POWER"GND";
"A"11;
%"PT5161LRS"
"5","(-2325,3525)","0","pure_quanta","I17";
;
LOCATION"U6013"
$SEC"5"
CDS_SEC"5"
PART_TYPE"SMLF"
VALUE"PT5161LRS"
MATERIAL"IC"
NEEDS_NO_SIZE"TRUE"
CDS_LMAN_SYM_OUTLINE"-350,2150,300,-2150"
CDS_LIB"pure_quanta"
PART_NUMBER"AJ051610U03";
"GND151"
$PN"V35"11;
"GND150"
$PN"V1"11;
"GND149"
$PN"U34"11;
"GND148"
$PN"U2"11;
"GND147"
$PN"T4"11;
"GND146"
$PN"T32"11;
"GND145"
$PN"T22"11;
"GND144"
$PN"T13"11;
"GND143"
$PN"L35"11;
"GND142"
$PN"L1"11;
"GND141"
$PN"K34"11;
"GND140"
$PN"K2"11;
"GND139"
$PN"J4"11;
"GND138"
$PN"J22"11;
"GND137"
$PN"H31"11;
"GND136"
$PN"H19"11;
"GND135"
$PN"H16"11;
"GND134"
$PN"H12"11;
"GND133"
$PN"FJ19"11;
"GND132"
$PN"FJ12"11;
"GND131"
$PN"FF21"11;
"GND130"
$PN"FF14"11;
"GND129"
$PN"FD35"11;
"GND128"
$PN"FD1"11;
"GND127"
$PN"FC9"11;
"GND126"
$PN"FC6"11;
"GND125"
$PN"FC3"11;
"GND124"
$PN"FC28"11;
"GND123"
$PN"FC25"11;
"GND122"
$PN"FC23"11;
"GND121"
$PN"FC19"11;
"GND120"
$PN"FB34"11;
"GND119"
$PN"FB2"11;
"GND118"
$PN"FA32"11;
"GND117"
$PN"FA15"11;
"GND116"
$PN"ET35"11;
"GND115"
$PN"ET1"11;
"GND114"
$PN"ER34"11;
"GND113"
$PN"ER2"11;
"GND112"
$PN"EP4"11;
"GND111"
$PN"EP32"11;
"GND110"
$PN"EP22"11;
"GND109"
$PN"EP13"11;
"GND108"
$PN"EJ35"11;
"GND107"
$PN"EJ1"11;
"GND106"
$PN"EH34"11;
"GND105"
$PN"EH2"11;
"GND104"
$PN"EG4"11;
"GND103"
$PN"EG32"11;
"GND102"
$PN"EG22"11;
"GND101"
$PN"EG13"11;
"GND100"
$PN"EB35"11;
"GND99"
$PN"EB1"11;
"GND98"
$PN"EA34"11;
"GND97"
$PN"EA2"11;
"GND96"
$PN"E33"11;
"GND95"
$PN"E27"11;
"GND94"
$PN"E14"11;
"GND93"
$PN"DY4"11;
"GND92"
$PN"DY32"11;
"GND91"
$PN"DY22"11;
"GND90"
$PN"DY13"11;
"GND89"
$PN"DR35"11;
"GND88"
$PN"DR1"11;
"GND87"
$PN"DP34"11;
"GND86"
$PN"DP2"11;
"GND85"
$PN"DN4"11;
"GND84"
$PN"DN32"11;
"GND83"
$PN"DN22"11;
"NCF_GND12"
$PN"FH34"10;
"NCF_GND11"
$PN"FH2"10;
"NCF_GND10"
$PN"FG35"10;
"NCF_GND9"
$PN"FG1"10;
"NCF_GND8"
$PN"FE34"10;
"NCF_GND7"
$PN"FE2"10;
"NCF_GND6"
$PN"D35"10;
"NCF_GND5"
$PN"D1"10;
"NCF_GND4"
$PN"C34"10;
"NCF_GND3"
$PN"C2"10;
"NCF_GND2"
$PN"A35"10;
"NCF_GND1"
$PN"A1"9;
"GND82"
$PN"DN13"8;
"GND81"
$PN"DH35"8;
"GND80"
$PN"DH1"8;
"GND79"
$PN"DG34"8;
"GND78"
$PN"DG2"8;
"GND77"
$PN"DF4"8;
"GND76"
$PN"DF32"8;
"GND75"
$PN"DF22"8;
"GND74"
$PN"DF13"8;
"GND73"
$PN"DA35"8;
"GND72"
$PN"DA1"8;
"GND71"
$PN"CY34"8;
"GND70"
$PN"CY2"8;
"GND69"
$PN"CW4"8;
"GND68"
$PN"CW32"8;
"GND67"
$PN"CW22"8;
"GND66"
$PN"CW13"8;
"GND65"
$PN"CP35"8;
"GND64"
$PN"CP1"8;
"GND63"
$PN"CN34"8;
"GND62"
$PN"CN2"8;
"GND61"
$PN"CM4"8;
"GND60"
$PN"CM32"8;
"GND59"
$PN"CM22"8;
"GND58"
$PN"CM13"8;
"GND57"
$PN"CG35"8;
"GND56"
$PN"CG1"8;
"GND55"
$PN"CF34"8;
"GND54"
$PN"CF2"8;
"GND53"
$PN"CE4"8;
"GND52"
$PN"CE32"8;
"GND51"
$PN"CE22"8;
"GND50"
$PN"CE13"8;
"GND49"
$PN"BY35"8;
"GND48"
$PN"BY1"8;
"GND47"
$PN"BW34"8;
"GND46"
$PN"BW2"8;
"GND45"
$PN"BV4"8;
"GND44"
$PN"BV32"8;
"GND43"
$PN"BV22"8;
"GND42"
$PN"BV13"8;
"GND41"
$PN"BN35"8;
"GND40"
$PN"BN1"8;
"GND39"
$PN"BM34"8;
"GND38"
$PN"BM2"8;
"GND37"
$PN"BL4"8;
"GND36"
$PN"BL32"8;
"GND35"
$PN"BL22"8;
"GND34"
$PN"BL13"8;
"GND33"
$PN"BF35"8;
"GND32"
$PN"BF1"8;
"GND31"
$PN"BE34"8;
"GND30"
$PN"BE2"8;
"GND29"
$PN"BD4"8;
"GND28"
$PN"BD32"8;
"GND27"
$PN"BD22"8;
"GND26"
$PN"BD13"8;
"GND25"
$PN"B19"8;
"GND24"
$PN"AW35"8;
"GND23"
$PN"AW1"8;
"GND22"
$PN"AV34"8;
"GND21"
$PN"AV2"8;
"GND20"
$PN"AU4"8;
"GND19"
$PN"AU32"8;
"GND18"
$PN"AU22"8;
"GND17"
$PN"AU13"8;
"GND16"
$PN"AM35"8;
"GND15"
$PN"AM1"8;
"GND14"
$PN"AL34"8;
"GND13"
$PN"AL2"8;
"GND12"
$PN"AK4"8;
"GND11"
$PN"AK32"8;
"GND10"
$PN"AK22"8;
"GND9"
$PN"AK13"8;
"GND8"
$PN"AE35"8;
"GND7"
$PN"AE1"8;
"GND6"
$PN"AD34"8;
"GND5"
$PN"AD2"8;
"GND4"
$PN"AC4"8;
"GND3"
$PN"AC32"8;
"GND2"
$PN"AC22"8;
"GND1"
$PN"AC13"8;
%"Q_RES"
"2","(-7550,3300)","0","pure_quanta","I18";
;
LOCATION"R1124"
$SEC"1"
CDS_SEC"1"
VALUE"200"
TOLERANCE"1%"
MATERIAL"CHIP"
PACK_TYPE"0201LF"
WATTAGE"1/20W"
CDS_LIB"pure_quanta"
PART_NUMBER"CS12001FE12";
"A"
$PN"1"14;
"B"
$PN"2"4;
%"Q_RES"
"2","(-8575,3850)","0","pure_quanta","I19";
;
LOCATION"R1123"
$SEC"1"
CDS_SEC"1"
VALUE"1K"
TOLERANCE"1%"
WATTAGE"1/20W"
MATERIAL"EMPTY"
PACK_TYPE"0201LF"
CDS_LIB"pure_quanta"
PART_NUMBER"CS21001FE07";
"A"
$PN"1"1;
"B"
$PN"2"14;
%"P1V0"
"1","(-8250,4350)","0","pure_quanta_power","I3";
;
HDL_POWER"P1V8_CPU0_RT3_1A_1D"
CDS_LIB"pure_quanta_power";
"A"13;
%"UNIVERSAL_GND"
"1","(-7550,3050)","0","pure_quanta_power","I4";
;
CDS_LIB"pure_quanta_power"
HDL_POWER"GND";
"A"4;
%"PT5161LRS"
"4","(-6400,4100)","0","pure_quanta","I6";
;
LOCATION"U6013"
$SEC"4"
CDS_SEC"4"
VALUE"PT5161LRS"
PART_TYPE"SMLF"
MATERIAL"IC"
NEEDS_NO_SIZE"TRUE"
CDS_LMAN_SYM_OUTLINE"-450,750,400,-750"
CDS_LIB"pure_quanta"
PART_NUMBER"AJ051610U03";
"PWR_2A_20"
$PN"T20"7;
"PWR_2A_19"
$PN"T17"7;
"PWR_2A_18"
$PN"EP20"7;
"PWR_2A_17"
$PN"EP17"7;
"PWR_2A_16"
$PN"EG20"7;
"PWR_2A_15"
$PN"EG17"7;
"PWR_2A_14"
$PN"DY20"7;
"PWR_2A_13"
$PN"DY17"7;
"PWR_2A_12"
$PN"DN20"7;
"PWR_2A_11"
$PN"DN17"7;
"PWR_2A_10"
$PN"DF20"5;
"PWR_2A_9"
$PN"DF17"5;
"PWR_2A_8"
$PN"BD20"5;
"PWR_2A_7"
$PN"BD17"5;
"PWR_2A_6"
$PN"AU20"7;
"PWR_2A_5"
$PN"AU17"7;
"PWR_2A_4"
$PN"AK20"7;
"PWR_2A_3"
$PN"AK17"7;
"PWR_2A_2"
$PN"AC20"7;
"PWR_2A_1"
$PN"AC17"7;
"PWR_1D"
$PN"BV17"13;
"PWR_2D_4"
$PN"CW20"12;
"PWR_2D_3"
$PN"CW17"12;
"PWR_2D_2"
$PN"BL20"12;
"PWR_2D_1"
$PN"BL17"12;
"PWR_1A_5"
$PN"CM20"6;
"PWR_1A_4"
$PN"CM17"6;
"PWR_1A_3"
$PN"CE20"6;
"PWR_1A_2"
$PN"CE17"6;
"PWR_1A_1"
$PN"BV20"6;
"VQPS"
$PN"G1"14;
%"P1V0"
"1","(-4550,3750)","0","pure_quanta_power","I7";
;
HDL_POWER"P0V9_CPU0_RT_2D"
CDS_LIB"pure_quanta_power";
"A"12;
%"P1V0"
"1","(-7675,4800)","0","pure_quanta_power","I8";
;
HDL_POWER"P1V8_CPU0_RT3_1A"
CDS_LIB"pure_quanta_power";
"A"6;
%"VCC_CORE"
"1","(-5150,4500)","0","pure_quanta_power","I9";
;
HDL_POWER"P0V9_CPU0_RT3_2A_2D"
CDS_LIB"pure_quanta_power";
"A"5;
END.
